(kicad_pcb
	(version 20260206)
	(generator "pcbnew")
	(generator_version "10.0")
	(general
		(thickness 1.6)
		(legacy_teardrops no)
	)
	(paper "A4")
	(title_block
		(title "peb — Lightning_PEB_BRD.brd")
		(comment 1 "Lightning (Wiwynn / Facebook NVMe JBOF) / footprints 1693-1700 of 2563")
	)
	(layers
		(0 "F.Cu" signal "TOP")
		(4 "In1.Cu" signal "L2GND")
		(6 "In2.Cu" signal "L3")
		(8 "In3.Cu" signal "L4VCC")
		(10 "In4.Cu" signal "L5VCC")
		(12 "In5.Cu" signal "L6")
		(14 "In6.Cu" signal "L7GND")
		(2 "B.Cu" signal "BOTTOM")
		(9 "F.Adhes" user "F.Adhesive")
		(11 "B.Adhes" user "B.Adhesive")
		(13 "F.Paste" user "Package Geometry/Pastemask Top")
		(15 "B.Paste" user "Package Geometry/Pastemask Bottom")
		(5 "F.SilkS" user "Ref Des/Silkscreen Top")
		(7 "B.SilkS" user "Ref Des/Silkscreen Bottom")
		(1 "F.Mask" user "Board Geometry/Soldermask Top")
		(3 "B.Mask" user "Board Geometry/Soldermask Bottom")
		(17 "Dwgs.User" user "User.Drawings")
		(19 "Cmts.User" user "User.Comments")
		(21 "Eco1.User" user "User.Eco1")
		(23 "Eco2.User" user "User.Eco2")
		(25 "Edge.Cuts" user "Board Geometry/Outline")
		(27 "Margin" user)
		(31 "F.CrtYd" user "Package Geometry/Place Bound Top")
		(29 "B.CrtYd" user "Package Geometry/Place Bound Bottom")
		(35 "F.Fab" user "Ref Des/Assembly Top")
		(33 "B.Fab" user "Ref Des/Assembly Bottom")
	)
	(footprint ""
		(layer "B.Cu")
		(at 48.5648 -102.4382 -90)
		(property "Reference" "R66"
			(at 0 0 90)
			(layer "B.SilkS")
			(hide yes)
			(effects
				(font
					(size 1.27 1.27)
				)
				(justify mirror)
			)
		)
		(property "Value" "0R2J-2-GP"
			(at -0.064008 -3.993896 270)
			(unlocked yes)
			(layer "B.Fab")
			(hide yes)
			(effects
				(font
					(size 1.016 1.016)
					(thickness 0.1524)
				)
				(justify mirror)
			)
		)
		(property "Device Type" "R402H16"
			(at -0.064008 -5.517896 270)
			(unlocked yes)
			(layer "B.Fab")
			(hide yes)
			(effects
				(font
					(size 1.016 1.016)
					(thickness 0.1524)
				)
				(justify mirror)
			)
		)
		(duplicate_pad_numbers_are_jumpers no)
		(fp_line
			(start -0.508 -0.9398)
			(end 0.508 -0.9398)
			(stroke
				(width 0.1524)
				(type default)
			)
			(layer "B.SilkS")
		)
		(fp_line
			(start 0.508 -0.9398)
			(end 0.508 0.9398)
			(stroke
				(width 0.1524)
				(type default)
			)
			(layer "B.SilkS")
		)
		(fp_rect
			(start 0.508 0.9398)
			(end -0.508 -0.9398)
			(stroke
				(width 0)
				(type default)
			)
			(fill no)
			(layer "B.CrtYd")
		)
		(fp_rect
			(start 0.508 0.9398)
			(end -0.508 -0.9398)
			(stroke
				(width 0)
				(type default)
			)
			(fill no)
			(layer "B.Fab")
		)
		(pad "1" smd custom
			(at 0 -0.4445 90)
			(size 0.1397 0.1397)
			(layers "B.Cu" "B.Mask" "B.Paste")
			(net "BMC_I2C14_MINI8_SDA")
			(options
				(clearance outline)
				(anchor circle)
			)
			(primitives
				(gr_poly
					(pts
						(arc
							(start -0.1778 0.2794)
							(mid -0.249642 0.249642)
							(end -0.2794 0.1778)
						)
						(arc
							(start -0.2794 -0.1778)
							(mid -0.249642 -0.249642)
							(end -0.1778 -0.2794)
						)
						(arc
							(start 0.1778 -0.2794)
							(mid 0.249642 -0.249642)
							(end 0.2794 -0.1778)
						)
						(arc
							(start 0.2794 0.1778)
							(mid 0.249642 0.249642)
							(end 0.1778 0.2794)
						)
					)
					(width 0)
					(fill yes)
				)
			)
		)
		(pad "2" smd custom
			(at 0 0.4445 90)
			(size 0.1397 0.1397)
			(layers "B.Cu" "B.Mask" "B.Paste")
			(net "BMC_I2C14_MINI8_SDA_S")
			(options
				(clearance outline)
				(anchor circle)
			)
			(primitives
				(gr_poly
					(pts
						(arc
							(start -0.1778 0.2794)
							(mid -0.249642 0.249642)
							(end -0.2794 0.1778)
						)
						(arc
							(start -0.2794 -0.1778)
							(mid -0.249642 -0.249642)
							(end -0.1778 -0.2794)
						)
						(arc
							(start 0.1778 -0.2794)
							(mid 0.249642 -0.249642)
							(end 0.2794 -0.1778)
						)
						(arc
							(start 0.2794 0.1778)
							(mid 0.249642 0.249642)
							(end 0.1778 0.2794)
						)
					)
					(width 0)
					(fill yes)
				)
			)
		)
	)
	(footprint ""
		(layer "B.Cu")
		(at 133.141212 -205.849474)
		(property "Reference" "R3207"
			(at 0 0 0)
			(layer "B.SilkS")
			(hide yes)
			(effects
				(font
					(size 1.27 1.27)
				)
				(justify mirror)
			)
		)
		(property "Value" "0R2J-2-GP"
			(at -0.064008 -3.993896 0)
			(unlocked yes)
			(layer "B.Fab")
			(hide yes)
			(effects
				(font
					(size 1.016 1.016)
					(thickness 0.1524)
				)
				(justify mirror)
			)
		)
		(property "Device Type" "R402H16"
			(at -0.064008 -5.517896 0)
			(unlocked yes)
			(layer "B.Fab")
			(hide yes)
			(effects
				(font
					(size 1.016 1.016)
					(thickness 0.1524)
				)
				(justify mirror)
			)
		)
		(duplicate_pad_numbers_are_jumpers no)
		(fp_line
			(start -0.508 -0.9398)
			(end 0.508 -0.9398)
			(stroke
				(width 0.1524)
				(type default)
			)
			(layer "B.SilkS")
		)
		(fp_line
			(start 0.508 -0.9398)
			(end 0.508 0.9398)
			(stroke
				(width 0.1524)
				(type default)
			)
			(layer "B.SilkS")
		)
		(fp_rect
			(start 0.508 0.9398)
			(end -0.508 -0.9398)
			(stroke
				(width 0)
				(type default)
			)
			(fill no)
			(layer "B.CrtYd")
		)
		(fp_rect
			(start 0.508 0.9398)
			(end -0.508 -0.9398)
			(stroke
				(width 0)
				(type default)
			)
			(fill no)
			(layer "B.Fab")
		)
		(pad "1" smd custom
			(at 0 -0.4445 180)
			(size 0.1397 0.1397)
			(layers "B.Cu" "B.Mask" "B.Paste")
			(net "SSD_PERST#2")
			(options
				(clearance outline)
				(anchor circle)
			)
			(primitives
				(gr_poly
					(pts
						(arc
							(start -0.1778 0.2794)
							(mid -0.249642 0.249642)
							(end -0.2794 0.1778)
						)
						(arc
							(start -0.2794 -0.1778)
							(mid -0.249642 -0.249642)
							(end -0.1778 -0.2794)
						)
						(arc
							(start 0.1778 -0.2794)
							(mid 0.249642 -0.249642)
							(end 0.2794 -0.1778)
						)
						(arc
							(start 0.2794 0.1778)
							(mid 0.249642 0.249642)
							(end 0.1778 0.2794)
						)
					)
					(width 0)
					(fill yes)
				)
			)
		)
		(pad "2" smd custom
			(at 0 0.4445 180)
			(size 0.1397 0.1397)
			(layers "B.Cu" "B.Mask" "B.Paste")
			(net "SSD_PERST#0_B2")
			(options
				(clearance outline)
				(anchor circle)
			)
			(primitives
				(gr_poly
					(pts
						(arc
							(start -0.1778 0.2794)
							(mid -0.249642 0.249642)
							(end -0.2794 0.1778)
						)
						(arc
							(start -0.2794 -0.1778)
							(mid -0.249642 -0.249642)
							(end -0.1778 -0.2794)
						)
						(arc
							(start 0.1778 -0.2794)
							(mid 0.249642 -0.249642)
							(end 0.2794 -0.1778)
						)
						(arc
							(start 0.2794 0.1778)
							(mid 0.249642 0.249642)
							(end 0.1778 0.2794)
						)
					)
					(width 0)
					(fill yes)
				)
			)
		)
	)
	(footprint ""
		(layer "B.Cu")
		(at 161.417 -92.7354)
		(property "Reference" "C717"
			(at 0 0 0)
			(layer "B.SilkS")
			(hide yes)
			(effects
				(font
					(size 1.27 1.27)
				)
				(justify mirror)
			)
		)
		(property "Value" "SCD1U10V2KX-5GP"
			(at -1.1811 -2.7051 0)
			(unlocked yes)
			(layer "B.Fab")
			(hide yes)
			(effects
				(font
					(size 1.016 1.016)
					(thickness 0.1524)
				)
				(justify mirror)
			)
		)
		(property "Device Type" "C402H22"
			(at -1.1811 -4.2291 0)
			(unlocked yes)
			(layer "B.Fab")
			(hide yes)
			(effects
				(font
					(size 1.016 1.016)
					(thickness 0.1524)
				)
				(justify mirror)
			)
		)
		(duplicate_pad_numbers_are_jumpers no)
		(fp_rect
			(start 0.4318 0.9525)
			(end -0.4318 -0.9525)
			(stroke
				(width 0)
				(type default)
			)
			(fill no)
			(layer "B.CrtYd")
		)
		(fp_rect
			(start 0.4318 0.9525)
			(end -0.4318 -0.9525)
			(stroke
				(width 0)
				(type default)
			)
			(fill no)
			(layer "B.Fab")
		)
		(pad "1" smd custom
			(at 0 -0.4445 180)
			(size 0.1524 0.1524)
			(layers "B.Cu" "B.Mask" "B.Paste")
			(net "P1V8_CLKGEN")
			(options
				(clearance outline)
				(anchor circle)
			)
			(primitives
				(gr_poly
					(pts
						(arc
							(start 0.3048 0.2032)
							(mid 0.275042 0.275042)
							(end 0.2032 0.3048)
						)
						(arc
							(start -0.2032 0.3048)
							(mid -0.275042 0.275042)
							(end -0.3048 0.2032)
						)
						(arc
							(start -0.3048 -0.2032)
							(mid -0.275042 -0.275042)
							(end -0.2032 -0.3048)
						)
						(arc
							(start 0.2032 -0.3048)
							(mid 0.275042 -0.275042)
							(end 0.3048 -0.2032)
						)
					)
					(width 0)
					(fill yes)
				)
			)
		)
		(pad "2" smd custom
			(at 0 0.4445 180)
			(size 0.1524 0.1524)
			(layers "B.Cu" "B.Mask" "B.Paste")
			(net "GND")
			(options
				(clearance outline)
				(anchor circle)
			)
			(primitives
				(gr_poly
					(pts
						(arc
							(start 0.3048 0.2032)
							(mid 0.275042 0.275042)
							(end 0.2032 0.3048)
						)
						(arc
							(start -0.2032 0.3048)
							(mid -0.275042 0.275042)
							(end -0.3048 0.2032)
						)
						(arc
							(start -0.3048 -0.2032)
							(mid -0.275042 -0.275042)
							(end -0.2032 -0.3048)
						)
						(arc
							(start 0.2032 -0.3048)
							(mid 0.275042 -0.275042)
							(end 0.3048 -0.2032)
						)
					)
					(width 0)
					(fill yes)
				)
			)
		)
	)
	(footprint ""
		(layer "B.Cu")
		(at 72.874124 -195.681092 180)
		(property "Reference" "R4116"
			(at 0 0 0)
			(layer "B.SilkS")
			(hide yes)
			(effects
				(font
					(size 1.27 1.27)
				)
				(justify mirror)
			)
		)
		(property "Value" "4K7R2F-GP"
			(at -0.064008 -3.993896 180)
			(unlocked yes)
			(layer "B.Fab")
			(hide yes)
			(effects
				(font
					(size 1.016 1.016)
					(thickness 0.1524)
				)
				(justify mirror)
			)
		)
		(property "Device Type" "R402H16"
			(at -0.064008 -5.517896 180)
			(unlocked yes)
			(layer "B.Fab")
			(hide yes)
			(effects
				(font
					(size 1.016 1.016)
					(thickness 0.1524)
				)
				(justify mirror)
			)
		)
		(duplicate_pad_numbers_are_jumpers no)
		(fp_line
			(start 0.508 -0.9398)
			(end 0.508 0.9398)
			(stroke
				(width 0.1524)
				(type default)
			)
			(layer "B.SilkS")
		)
		(fp_line
			(start -0.508 -0.9398)
			(end 0.508 -0.9398)
			(stroke
				(width 0.1524)
				(type default)
			)
			(layer "B.SilkS")
		)
		(fp_rect
			(start 0.508 0.9398)
			(end -0.508 -0.9398)
			(stroke
				(width 0)
				(type default)
			)
			(fill no)
			(layer "B.CrtYd")
		)
		(fp_rect
			(start 0.508 0.9398)
			(end -0.508 -0.9398)
			(stroke
				(width 0)
				(type default)
			)
			(fill no)
			(layer "B.Fab")
		)
		(pad "1" smd custom
			(at 0 -0.4445)
			(size 0.1397 0.1397)
			(layers "B.Cu" "B.Mask" "B.Paste")
			(net "SSD_PERST#11")
			(options
				(clearance outline)
				(anchor circle)
			)
			(primitives
				(gr_poly
					(pts
						(arc
							(start -0.1778 0.2794)
							(mid -0.249642 0.249642)
							(end -0.2794 0.1778)
						)
						(arc
							(start -0.2794 -0.1778)
							(mid -0.249642 -0.249642)
							(end -0.1778 -0.2794)
						)
						(arc
							(start 0.1778 -0.2794)
							(mid 0.249642 -0.249642)
							(end 0.2794 -0.1778)
						)
						(arc
							(start 0.2794 0.1778)
							(mid 0.249642 0.249642)
							(end 0.1778 0.2794)
						)
					)
					(width 0)
					(fill yes)
				)
			)
		)
		(pad "2" smd custom
			(at 0 0.4445)
			(size 0.1397 0.1397)
			(layers "B.Cu" "B.Mask" "B.Paste")
			(net "P3V3_STBY")
			(options
				(clearance outline)
				(anchor circle)
			)
			(primitives
				(gr_poly
					(pts
						(arc
							(start -0.1778 0.2794)
							(mid -0.249642 0.249642)
							(end -0.2794 0.1778)
						)
						(arc
							(start -0.2794 -0.1778)
							(mid -0.249642 -0.249642)
							(end -0.1778 -0.2794)
						)
						(arc
							(start 0.1778 -0.2794)
							(mid 0.249642 -0.249642)
							(end 0.2794 -0.1778)
						)
						(arc
							(start 0.2794 0.1778)
							(mid 0.249642 0.249642)
							(end 0.1778 0.2794)
						)
					)
					(width 0)
					(fill yes)
				)
			)
		)
	)
	(footprint ""
		(layer "B.Cu")
		(at 251.333 -47.117 -90)
		(property "Reference" "C611"
			(at 0 0 90)
			(layer "B.SilkS")
			(hide yes)
			(effects
				(font
					(size 1.27 1.27)
				)
				(justify mirror)
			)
		)
		(property "Value" "SCD1U16V1KX-1-GP"
			(at 2.8321 -1.7399 270)
			(unlocked yes)
			(layer "B.Fab")
			(hide yes)
			(effects
				(font
					(size 1.016 1.016)
					(thickness 0.1524)
				)
				(justify mirror)
			)
		)
		(property "Device Type" "C0201H13"
			(at 2.8321 -3.2639 270)
			(unlocked yes)
			(layer "B.Fab")
			(hide yes)
			(effects
				(font
					(size 1.016 1.016)
					(thickness 0.1524)
				)
				(justify mirror)
			)
		)
		(duplicate_pad_numbers_are_jumpers no)
		(fp_rect
			(start 0.2794 0.6477)
			(end -0.2794 -0.6477)
			(stroke
				(width 0)
				(type default)
			)
			(fill no)
			(layer "B.CrtYd")
		)
		(fp_rect
			(start 0.2794 0.6477)
			(end -0.2794 -0.6477)
			(stroke
				(width 0)
				(type default)
			)
			(fill no)
			(layer "B.Fab")
		)
		(pad "1" smd custom
			(at 0 -0.2794 90)
			(size 0.0762 0.0762)
			(layers "B.Cu" "B.Mask" "B.Paste")
			(net "DUT_AVD_PCIE")
			(options
				(clearance outline)
				(anchor circle)
			)
			(primitives
				(gr_poly
					(pts
						(arc
							(start 0.1524 0.127)
							(mid 0.137521 0.162921)
							(end 0.1016 0.1778)
						)
						(arc
							(start -0.1016 0.1778)
							(mid -0.137521 0.162921)
							(end -0.1524 0.127)
						)
						(arc
							(start -0.1524 -0.127)
							(mid -0.137521 -0.162921)
							(end -0.1016 -0.1778)
						)
						(arc
							(start 0.1016 -0.1778)
							(mid 0.137521 -0.162921)
							(end 0.1524 -0.127)
						)
					)
					(width 0)
					(fill yes)
				)
			)
		)
		(pad "2" smd custom
			(at 0 0.2794 90)
			(size 0.0762 0.0762)
			(layers "B.Cu" "B.Mask" "B.Paste")
			(net "GND")
			(options
				(clearance outline)
				(anchor circle)
			)
			(primitives
				(gr_poly
					(pts
						(arc
							(start 0.1524 0.127)
							(mid 0.137521 0.162921)
							(end 0.1016 0.1778)
						)
						(arc
							(start -0.1016 0.1778)
							(mid -0.137521 0.162921)
							(end -0.1524 0.127)
						)
						(arc
							(start -0.1524 -0.127)
							(mid -0.137521 -0.162921)
							(end -0.1016 -0.1778)
						)
						(arc
							(start 0.1016 -0.1778)
							(mid 0.137521 -0.162921)
							(end 0.1524 -0.127)
						)
					)
					(width 0)
					(fill yes)
				)
			)
		)
	)
	(footprint ""
		(layer "B.Cu")
		(at 232.6005 -38.989 -90)
		(property "Reference" "TP201"
			(at 0 0 90)
			(layer "B.SilkS")
			(hide yes)
			(effects
				(font
					(size 1.27 1.27)
				)
				(justify mirror)
			)
		)
		(property "Value" "TPAD28-2-GP"
			(at 0.0127 -1.6637 270)
			(unlocked yes)
			(layer "B.Fab")
			(hide yes)
			(effects
				(font
					(size 1.016 1.016)
					(thickness 0.1524)
				)
				(justify mirror)
			)
		)
		(property "Device Type" "TPAD28"
			(at 0.0127 -3.1877 270)
			(unlocked yes)
			(layer "B.Fab")
			(hide yes)
			(effects
				(font
					(size 1.016 1.016)
					(thickness 0.1524)
				)
				(justify mirror)
			)
		)
		(duplicate_pad_numbers_are_jumpers no)
		(fp_poly
			(pts
				(arc
					(start 0 -0.3556)
					(mid 0 0.3556)
					(end 0 -0.3556)
				)
			)
			(stroke
				(width 0)
				(type default)
			)
			(fill no)
			(layer "B.CrtYd")
		)
		(fp_poly
			(pts
				(arc
					(start 0 -0.6096)
					(mid 0 0.6096)
					(end 0 -0.6096)
				)
			)
			(stroke
				(width 0)
				(type default)
			)
			(fill no)
			(layer "B.Fab")
		)
		(pad "1" smd circle
			(at 0 0 90)
			(size 0.7112 0.7112)
			(layers "B.Cu" "B.Mask" "B.Paste")
			(net "RMII_REF_CLK")
		)
	)
	(footprint ""
		(layer "B.Cu")
		(at 305.90109 -34.719514)
		(property "Reference" "C134"
			(at 0 0 0)
			(layer "B.SilkS")
			(hide yes)
			(effects
				(font
					(size 1.27 1.27)
				)
				(justify mirror)
			)
		)
		(property "Value" "SCD1U10V2KX-5GP"
			(at -1.1811 -2.7051 0)
			(unlocked yes)
			(layer "B.Fab")
			(hide yes)
			(effects
				(font
					(size 1.016 1.016)
					(thickness 0.1524)
				)
				(justify mirror)
			)
		)
		(property "Device Type" "C402H22"
			(at -1.1811 -4.2291 0)
			(unlocked yes)
			(layer "B.Fab")
			(hide yes)
			(effects
				(font
					(size 1.016 1.016)
					(thickness 0.1524)
				)
				(justify mirror)
			)
		)
		(duplicate_pad_numbers_are_jumpers no)
		(fp_rect
			(start 0.4318 0.9525)
			(end -0.4318 -0.9525)
			(stroke
				(width 0)
				(type default)
			)
			(fill no)
			(layer "B.CrtYd")
		)
		(fp_rect
			(start 0.4318 0.9525)
			(end -0.4318 -0.9525)
			(stroke
				(width 0)
				(type default)
			)
			(fill no)
			(layer "B.Fab")
		)
		(pad "1" smd custom
			(at 0 -0.4445 180)
			(size 0.1524 0.1524)
			(layers "B.Cu" "B.Mask" "B.Paste")
			(net "GND")
			(options
				(clearance outline)
				(anchor circle)
			)
			(primitives
				(gr_poly
					(pts
						(arc
							(start 0.3048 0.2032)
							(mid 0.275042 0.275042)
							(end 0.2032 0.3048)
						)
						(arc
							(start -0.2032 0.3048)
							(mid -0.275042 0.275042)
							(end -0.3048 0.2032)
						)
						(arc
							(start -0.3048 -0.2032)
							(mid -0.275042 -0.275042)
							(end -0.2032 -0.3048)
						)
						(arc
							(start 0.2032 -0.3048)
							(mid 0.275042 -0.275042)
							(end 0.3048 -0.2032)
						)
					)
					(width 0)
					(fill yes)
				)
			)
		)
		(pad "2" smd custom
			(at 0 0.4445 180)
			(size 0.1524 0.1524)
			(layers "B.Cu" "B.Mask" "B.Paste")
			(net "P3V3_STBY")
			(options
				(clearance outline)
				(anchor circle)
			)
			(primitives
				(gr_poly
					(pts
						(arc
							(start 0.3048 0.2032)
							(mid 0.275042 0.275042)
							(end 0.2032 0.3048)
						)
						(arc
							(start -0.2032 0.3048)
							(mid -0.275042 0.275042)
							(end -0.3048 0.2032)
						)
						(arc
							(start -0.3048 -0.2032)
							(mid -0.275042 -0.275042)
							(end -0.2032 -0.3048)
						)
						(arc
							(start 0.2032 -0.3048)
							(mid 0.275042 -0.275042)
							(end 0.3048 -0.2032)
						)
					)
					(width 0)
					(fill yes)
				)
			)
		)
	)
	(footprint ""
		(layer "B.Cu")
		(at 66.802 -191.516)
		(property "Reference" "R3235"
			(at 0 0 0)
			(layer "B.SilkS")
			(hide yes)
			(effects
				(font
					(size 1.27 1.27)
				)
				(justify mirror)
			)
		)
		(property "Value" "0R2J-2-GP"
			(at -0.064008 -3.993896 0)
			(unlocked yes)
			(layer "B.Fab")
			(hide yes)
			(effects
				(font
					(size 1.016 1.016)
					(thickness 0.1524)
				)
				(justify mirror)
			)
		)
		(property "Device Type" "R402H16"
			(at -0.064008 -5.517896 0)
			(unlocked yes)
			(layer "B.Fab")
			(hide yes)
			(effects
				(font
					(size 1.016 1.016)
					(thickness 0.1524)
				)
				(justify mirror)
			)
		)
		(duplicate_pad_numbers_are_jumpers no)
		(fp_line
			(start -0.508 -0.9398)
			(end 0.508 -0.9398)
			(stroke
				(width 0.1524)
				(type default)
			)
			(layer "B.SilkS")
		)
		(fp_line
			(start 0.508 -0.9398)
			(end 0.508 0.9398)
			(stroke
				(width 0.1524)
				(type default)
			)
			(layer "B.SilkS")
		)
		(fp_rect
			(start 0.508 0.9398)
			(end -0.508 -0.9398)
			(stroke
				(width 0)
				(type default)
			)
			(fill no)
			(layer "B.CrtYd")
		)
		(fp_rect
			(start 0.508 0.9398)
			(end -0.508 -0.9398)
			(stroke
				(width 0)
				(type default)
			)
			(fill no)
			(layer "B.Fab")
		)
		(pad "1" smd custom
			(at 0 -0.4445 180)
			(size 0.1397 0.1397)
			(layers "B.Cu" "B.Mask" "B.Paste")
			(net "BMC_SSD_RST#11")
			(options
				(clearance outline)
				(anchor circle)
			)
			(primitives
				(gr_poly
					(pts
						(arc
							(start -0.1778 0.2794)
							(mid -0.249642 0.249642)
							(end -0.2794 0.1778)
						)
						(arc
							(start -0.2794 -0.1778)
							(mid -0.249642 -0.249642)
							(end -0.1778 -0.2794)
						)
						(arc
							(start 0.1778 -0.2794)
							(mid 0.249642 -0.249642)
							(end 0.2794 -0.1778)
						)
						(arc
							(start 0.2794 0.1778)
							(mid 0.249642 0.249642)
							(end 0.1778 0.2794)
						)
					)
					(width 0)
					(fill yes)
				)
			)
		)
		(pad "2" smd custom
			(at 0 0.4445 180)
			(size 0.1397 0.1397)
			(layers "B.Cu" "B.Mask" "B.Paste")
			(net "BMC_SSD_RST#0_A11")
			(options
				(clearance outline)
				(anchor circle)
			)
			(primitives
				(gr_poly
					(pts
						(arc
							(start -0.1778 0.2794)
							(mid -0.249642 0.249642)
							(end -0.2794 0.1778)
						)
						(arc
							(start -0.2794 -0.1778)
							(mid -0.249642 -0.249642)
							(end -0.1778 -0.2794)
						)
						(arc
							(start 0.1778 -0.2794)
							(mid 0.249642 -0.249642)
							(end 0.2794 -0.1778)
						)
						(arc
							(start 0.2794 0.1778)
							(mid 0.249642 0.249642)
							(end 0.1778 0.2794)
						)
					)
					(width 0)
					(fill yes)
				)
			)
		)
	)
)
